# TIMECARD (Time Appliance Project (Time Card)) — schematic netlist excerpt (pin names and nets, part order shuffled) for the footprints in the layout excerpt that follows; sources: Cadence DE-HDL packaged netlist, KiCad conversion of R4006-B0001-02_R01.brd

SP33  SOLDER_PREFORM  pkg 0201_SOLDER_PREFORM_4MIL  page 34 : \1\ = NC ; \2\ = NC
FU1  FUSE  2.5A  pkg SMC_0603R_H022  page 27 : \1\ = XP12R0V_IN ; \2\ = XP12R0V
R325  RESISTOR  10KOHM 1%  pkg SMC_0402R_H016  page 25 : \1\ = XP3R3V_FPGA ; \2\ = FPGA_IO_6

(kicad_pcb
	(version 20260206)
	(generator "pcbnew")
	(generator_version "10.0")
	(general
		(thickness 1.6)
		(legacy_teardrops no)
	)
	(paper "A4")
	(title_block
		(title "timecard-production-celestica-r4006 — R4006-B0001-02_R01.brd")
		(comment 1 "Time Appliance Project (Time Card) / footprints 384-386 of 1113")
	)
	(layers
		(0 "F.Cu" signal "TOP")
		(4 "In1.Cu" signal "L02_GND1")
		(6 "In2.Cu" signal "L03_SIG1")
		(8 "In3.Cu" signal "L04_GND2")
		(10 "In4.Cu" signal "L05_VCC1")
		(12 "In5.Cu" signal "L06_VCC2")
		(14 "In6.Cu" signal "L07_GND3")
		(16 "In7.Cu" signal "L08_SIG2")
		(18 "In8.Cu" signal "L09_GND4")
		(2 "B.Cu" signal "BOTTOM")
		(9 "F.Adhes" user "F.Adhesive")
		(11 "B.Adhes" user "B.Adhesive")
		(13 "F.Paste" user "Package Geometry/Pastemask Top")
		(15 "B.Paste" user "Package Geometry/Pastemask Bottom")
		(5 "F.SilkS" user "Ref Des/Silkscreen Top")
		(7 "B.SilkS" user "Ref Des/Silkscreen Bottom")
		(1 "F.Mask" user "Board Geometry/Soldermask Top")
		(3 "B.Mask" user "Board Geometry/Soldermask Bottom")
		(17 "Dwgs.User" user "User.Drawings")
		(19 "Cmts.User" user "User.Comments")
		(21 "Eco1.User" user "User.Eco1")
		(23 "Eco2.User" user "User.Eco2")
		(25 "Edge.Cuts" user "Board Geometry/Outline")
		(27 "Margin" user)
		(31 "F.CrtYd" user "Package Geometry/Place Bound Top")
		(29 "B.CrtYd" user "Package Geometry/Place Bound Bottom")
		(35 "F.Fab" user "Ref Des/Assembly Top")
		(33 "B.Fab" user "Ref Des/Assembly Bottom")
	)
	(footprint ""
		(layer "F.Cu")
		(at 106.9086 -64.2874 -90)
		(property "Reference" "R325"
			(at 0.0254 -2.22377 90)
			(unlocked yes)
			(layer "F.SilkS")
			(effects
				(font
					(size 0.7874 0.5842)
					(thickness 0.1524)
				)
			)
		)
		(property "Value" "VAL*"
			(at 0.02032 2.13233 270)
			(unlocked yes)
			(layer "F.Fab")
			(hide yes)
			(effects
				(font
					(size 0.7874 0.5842)
					(thickness 0.1524)
				)
			)
		)
		(property "Tolerance" "TOL*"
			(at 0.044704 3.05435 270)
			(unlocked yes)
			(layer "Cmts.User")
			(hide yes)
			(effects
				(font
					(size 0.7874 0.5842)
					(thickness 0.1524)
				)
			)
		)
		(property "User Part Number" "PARTNUM*"
			(at 0.02032 4.024884 270)
			(unlocked yes)
			(layer "Cmts.User")
			(hide yes)
			(effects
				(font
					(size 0.7874 0.5842)
					(thickness 0.1524)
				)
			)
		)
		(property "Device Type" "RESISTOR-G155-11002-01,10KOHM,A"
			(at 0.008382 1.210564 270)
			(unlocked yes)
			(layer "F.Fab")
			(hide yes)
			(effects
				(font
					(size 0.7874 0.5842)
					(thickness 0.1524)
				)
			)
		)
		(duplicate_pad_numbers_are_jumpers no)
		(fp_line
			(start -1.143 0.5588)
			(end 1.143 0.5588)
			(stroke
				(width 0.1)
				(type default)
			)
			(layer "F.SilkS")
		)
		(fp_line
			(start 1.143 0.5588)
			(end 1.143 -0.5588)
			(stroke
				(width 0.1)
				(type default)
			)
			(layer "F.SilkS")
		)
		(fp_line
			(start -1.143 -0.5588)
			(end -1.143 0.5588)
			(stroke
				(width 0.1)
				(type default)
			)
			(layer "F.SilkS")
		)
		(fp_line
			(start 1.143 -0.5588)
			(end -1.143 -0.5588)
			(stroke
				(width 0.1)
				(type default)
			)
			(layer "F.SilkS")
		)
		(fp_poly
			(pts
				(xy -1.143 0.5588) (xy 1.143 0.5588) (xy 1.143 -0.5588) (xy -1.143 -0.5588)
			)
			(stroke
				(width 0)
				(type default)
			)
			(fill no)
			(layer "F.CrtYd")
		)
		(fp_line
			(start -0.508 0.3048)
			(end 0.508 0.3048)
			(stroke
				(width 0.1)
				(type default)
			)
			(layer "F.Fab")
		)
		(fp_line
			(start 0.508 0.3048)
			(end 0.508 -0.3048)
			(stroke
				(width 0.1)
				(type default)
			)
			(layer "F.Fab")
		)
		(fp_line
			(start -0.508 -0.3048)
			(end -0.508 0.3048)
			(stroke
				(width 0.1)
				(type default)
			)
			(layer "F.Fab")
		)
		(fp_line
			(start 0.508 -0.3048)
			(end -0.508 -0.3048)
			(stroke
				(width 0.1)
				(type default)
			)
			(layer "F.Fab")
		)
		(pad "1" smd rect
			(at -0.5334 0 270)
			(size 0.7112 0.6096)
			(layers "F.Cu" "F.Mask" "F.Paste")
			(net "XP3R3V_FPGA")
		)
		(pad "2" smd rect
			(at 0.5334 0 270)
			(size 0.7112 0.6096)
			(layers "F.Cu" "F.Mask" "F.Paste")
			(net "FPGA_IO_6")
		)
		(zone
			(layer "F.Cu")
			(hatch none 0.5)
			(connect_pads
				(clearance 0)
			)
			(min_thickness 0.25)
			(keepout
				(tracks allowed)
				(vias not_allowed)
				(pads allowed)
				(copperpour not_allowed)
				(footprints allowed)
			)
			(placement
				(enabled no)
				(sheetname "")
			)
			(fill
				(thermal_gap 0.5)
				(thermal_bridge_width 0.5)
				(island_removal_mode 0)
			)
			(polygon
				(pts
					(xy 106.6038 -64.3636) (xy 106.6038 -64.2112) (xy 107.2134 -64.2112) (xy 107.2134 -64.3636)
				)
			)
		)
		(zone
			(layer "F.Cu")
			(hatch none 0.5)
			(connect_pads
				(clearance 0)
			)
			(min_thickness 0.25)
			(keepout
				(tracks not_allowed)
				(vias allowed)
				(pads allowed)
				(copperpour not_allowed)
				(footprints allowed)
			)
			(placement
				(enabled no)
				(sheetname "")
			)
			(fill
				(thermal_gap 0.5)
				(thermal_bridge_width 0.5)
				(island_removal_mode 0)
			)
			(polygon
				(pts
					(xy 106.6038 -64.3636) (xy 106.6038 -64.2112) (xy 107.2134 -64.2112) (xy 107.2134 -64.3636)
				)
			)
		)
	)
	(footprint ""
		(layer "F.Cu")
		(at 139.8524 -90.6526 180)
		(property "Reference" "FU1"
			(at 2.4384 -0.39497 0)
			(unlocked yes)
			(layer "F.SilkS")
			(effects
				(font
					(size 0.7874 0.5842)
					(thickness 0.1524)
				)
			)
		)
		(property "Value" "VAL*"
			(at 0.0508 2.549906 180)
			(unlocked yes)
			(layer "F.Fab")
			(hide yes)
			(effects
				(font
					(size 0.7874 0.5842)
					(thickness 0.1524)
				)
			)
		)
		(property "Device Type" "FUSE-G280-10012-01,2.5A"
			(at 0.0254 1.584706 180)
			(unlocked yes)
			(layer "F.Fab")
			(hide yes)
			(effects
				(font
					(size 0.7874 0.5842)
					(thickness 0.1524)
				)
			)
		)
		(property "User Part Number" "PARTNUM*"
			(at 0.0762 4.480306 180)
			(unlocked yes)
			(layer "Cmts.User")
			(hide yes)
			(effects
				(font
					(size 0.7874 0.5842)
					(thickness 0.1524)
				)
			)
		)
		(property "Tolerance" "TOL*"
			(at 0.0508 3.515106 180)
			(unlocked yes)
			(layer "Cmts.User")
			(hide yes)
			(effects
				(font
					(size 0.7874 0.5842)
					(thickness 0.1524)
				)
			)
		)
		(duplicate_pad_numbers_are_jumpers no)
		(fp_line
			(start 1.3208 0.7112)
			(end -1.3208 0.7112)
			(stroke
				(width 0.1)
				(type default)
			)
			(layer "F.SilkS")
		)
		(fp_line
			(start 1.3208 -0.7112)
			(end 1.3208 0.7112)
			(stroke
				(width 0.1)
				(type default)
			)
			(layer "F.SilkS")
		)
		(fp_line
			(start -1.3208 0.7112)
			(end -1.3208 -0.7112)
			(stroke
				(width 0.1)
				(type default)
			)
			(layer "F.SilkS")
		)
		(fp_line
			(start -1.3208 -0.7112)
			(end 1.3208 -0.7112)
			(stroke
				(width 0.1)
				(type default)
			)
			(layer "F.SilkS")
		)
		(fp_rect
			(start 1.3208 -0.7112)
			(end -1.3208 0.7112)
			(stroke
				(width 0)
				(type default)
			)
			(fill no)
			(layer "F.CrtYd")
		)
		(fp_line
			(start 0.8128 0.4572)
			(end -0.8128 0.4572)
			(stroke
				(width 0.1)
				(type default)
			)
			(layer "F.Fab")
		)
		(fp_line
			(start 0.8128 -0.4572)
			(end 0.8128 0.4572)
			(stroke
				(width 0.1)
				(type default)
			)
			(layer "F.Fab")
		)
		(fp_line
			(start -0.8128 0.4572)
			(end -0.8128 -0.4572)
			(stroke
				(width 0.1)
				(type default)
			)
			(layer "F.Fab")
		)
		(fp_line
			(start -0.8128 -0.4572)
			(end 0.8128 -0.4572)
			(stroke
				(width 0.1)
				(type default)
			)
			(layer "F.Fab")
		)
		(pad "1" smd rect
			(at -0.6858 0 180)
			(size 0.762 0.8636)
			(layers "F.Cu" "F.Mask" "F.Paste")
			(net "XP12R0V_IN")
		)
		(pad "2" smd rect
			(at 0.6858 0 180)
			(size 0.762 0.8636)
			(layers "F.Cu" "F.Mask" "F.Paste")
			(net "XP12R0V")
		)
		(zone
			(layer "F.Cu")
			(hatch none 0.5)
			(connect_pads
				(clearance 0)
			)
			(min_thickness 0.25)
			(keepout
				(tracks allowed)
				(vias not_allowed)
				(pads allowed)
				(copperpour not_allowed)
				(footprints allowed)
			)
			(placement
				(enabled no)
				(sheetname "")
			)
			(fill
				(thermal_gap 0.5)
				(thermal_bridge_width 0.5)
				(island_removal_mode 0)
			)
			(polygon
				(pts
					(xy 139.7 -90.1954) (xy 140.0048 -90.1954) (xy 140.0048 -91.1098) (xy 139.7 -91.1098)
				)
			)
		)
	)
	(footprint ""
		(layer "F.Cu")
		(at 52.451 -131.699)
		(property "Reference" "SP33"
			(at 0 0 0)
			(layer "F.SilkS")
			(hide yes)
			(effects
				(font
					(size 1.27 1.27)
				)
			)
		)
		(property "Value" ""
			(at 0 0 0)
			(layer "F.Fab")
			(effects
				(font
					(size 1.27 1.27)
				)
			)
		)
		(duplicate_pad_numbers_are_jumpers no)
	)
)
